# BASEBOARD_FAB2 (Tioga Pass) — schematic netlist excerpt (pin names and nets, part order shuffled) for the footprints in the layout excerpt that follows; sources: Cadence DE-HDL packaged netlist, KiCad conversion of Wiwynn_Tioga_Pass_MB.brd

R1D36  RES  1.00K 1% CHIP  pkg 0402  page 199 : A = P12V_STBY ; B = A_HSC_VOUT
C4G5  SC22U16V5MX-4-GP  20%  pkg SMD-BCG5  page 233 : \1\ = VR_FET_SW_P12V_STBY_PVPP_GHJ ; \2\ = GND
C8G8  CAP  0.22UF 16V 10% X7R  pkg 0402  page 105 : A = P3E_CPU0_PE2_SS_TXP<1> ; B = P3E_CPU0_PE2_SS_C_TXP<1>

(kicad_pcb
	(version 20260206)
	(generator "pcbnew")
	(generator_version "10.0")
	(general
		(thickness 1.6)
		(legacy_teardrops no)
	)
	(paper "A4")
	(title_block
		(title "Wiwynn_Tioga_Pass_MB.brd")
		(comment 1 "Tioga Pass / footprints 1010-1012 of 4770")
	)
	(layers
		(0 "F.Cu" signal "TOP")
		(4 "In1.Cu" signal "L2GND")
		(6 "In2.Cu" signal "L3")
		(8 "In3.Cu" signal "L4GND")
		(10 "In4.Cu" signal "L5")
		(12 "In5.Cu" signal "L6GND")
		(14 "In6.Cu" signal "L7VCC")
		(16 "In7.Cu" signal "L8VCC")
		(18 "In8.Cu" signal "L9GND")
		(20 "In9.Cu" signal "L10")
		(22 "In10.Cu" signal "L11GND")
		(24 "In11.Cu" signal "L12")
		(26 "In12.Cu" signal "L13GND")
		(2 "B.Cu" signal "BOTTOM")
		(9 "F.Adhes" user "F.Adhesive")
		(11 "B.Adhes" user "B.Adhesive")
		(13 "F.Paste" user "Package Geometry/Pastemask Top")
		(15 "B.Paste" user "Package Geometry/Pastemask Bottom")
		(5 "F.SilkS" user "Ref Des/Silkscreen Top")
		(7 "B.SilkS" user "Ref Des/Silkscreen Bottom")
		(1 "F.Mask" user "Board Geometry/Soldermask Top")
		(3 "B.Mask" user "Board Geometry/Soldermask Bottom")
		(17 "Dwgs.User" user "User.Drawings")
		(19 "Cmts.User" user "User.Comments")
		(21 "Eco1.User" user "User.Eco1")
		(23 "Eco2.User" user "User.Eco2")
		(25 "Edge.Cuts" user "Board Geometry/Outline")
		(27 "Margin" user)
		(31 "F.CrtYd" user "Package Geometry/Place Bound Top")
		(29 "B.CrtYd" user "Package Geometry/Place Bound Bottom")
		(35 "F.Fab" user "Ref Des/Assembly Top")
		(33 "B.Fab" user "Ref Des/Assembly Bottom")
	)
	(footprint ""
		(layer "F.Cu")
		(at 14.224 -75.311 180)
		(property "Reference" "R1D36"
			(at 0 0 180)
			(layer "F.SilkS")
			(hide yes)
			(effects
				(font
					(size 1.27 1.27)
				)
			)
		)
		(property "Value" ""
			(at 0 0 180)
			(layer "F.Fab")
			(effects
				(font
					(size 1.27 1.27)
				)
			)
		)
		(duplicate_pad_numbers_are_jumpers no)
		(fp_rect
			(start -0.2794 -0.1016)
			(end 0.2794 0.9906)
			(stroke
				(width 0)
				(type default)
			)
			(fill no)
			(layer "F.CrtYd")
		)
		(fp_line
			(start 0.2794 0.9906)
			(end 0.2794 -0.1016)
			(stroke
				(width 0.1)
				(type default)
			)
			(layer "F.Fab")
		)
		(fp_line
			(start 0.2794 -0.1016)
			(end -0.2794 -0.1016)
			(stroke
				(width 0.1)
				(type default)
			)
			(layer "F.Fab")
		)
		(fp_line
			(start -0.2794 0.9906)
			(end 0.2794 0.9906)
			(stroke
				(width 0.1)
				(type default)
			)
			(layer "F.Fab")
		)
		(fp_line
			(start -0.2794 -0.1016)
			(end -0.2794 0.9906)
			(stroke
				(width 0.1)
				(type default)
			)
			(layer "F.Fab")
		)
		(pad "1" smd rect
			(at 0 0 180)
			(size 0.508 0.508)
			(layers "F.Cu" "F.Mask" "F.Paste")
			(net "P12V_STBY")
		)
		(pad "2" smd rect
			(at 0 0.889 180)
			(size 0.508 0.508)
			(layers "F.Cu" "F.Mask" "F.Paste")
			(net "A_HSC_VOUT")
		)
		(zone
			(layer "F.Cu")
			(hatch none 0.5)
			(connect_pads
				(clearance 0)
			)
			(min_thickness 0.25)
			(keepout
				(tracks allowed)
				(vias not_allowed)
				(pads allowed)
				(copperpour not_allowed)
				(footprints allowed)
			)
			(placement
				(enabled no)
				(sheetname "")
			)
			(fill
				(thermal_gap 0.5)
				(thermal_bridge_width 0.5)
				(island_removal_mode 0)
			)
			(polygon
				(pts
					(xy 14.478 -75.565) (xy 14.478 -75.946) (xy 13.97 -75.946) (xy 13.97 -75.565)
				)
			)
		)
		(zone
			(layer "F.Cu")
			(hatch none 0.5)
			(connect_pads
				(clearance 0)
			)
			(min_thickness 0.25)
			(keepout
				(tracks not_allowed)
				(vias allowed)
				(pads allowed)
				(copperpour not_allowed)
				(footprints allowed)
			)
			(placement
				(enabled no)
				(sheetname "")
			)
			(fill
				(thermal_gap 0.5)
				(thermal_bridge_width 0.5)
				(island_removal_mode 0)
			)
			(polygon
				(pts
					(xy 14.478 -75.565) (xy 14.478 -75.946) (xy 13.97 -75.946) (xy 13.97 -75.565)
				)
			)
		)
	)
	(footprint ""
		(layer "F.Cu")
		(at 184.421272 -9.119108 90)
		(property "Reference" "C4G5"
			(at 0 0 90)
			(layer "F.SilkS")
			(hide yes)
			(effects
				(font
					(size 1.27 1.27)
				)
			)
		)
		(property "Value" "*"
			(at -0.0762 -6.2357 90)
			(unlocked yes)
			(layer "F.Fab")
			(hide yes)
			(effects
				(font
					(size 1.27 1.016)
					(thickness 0.1524)
				)
			)
		)
		(property "Device Type" "SC22U16V5MX-4-GP_SMD-BCG5-SC22A"
			(at -0.0762 -8.2677 90)
			(unlocked yes)
			(layer "F.Fab")
			(hide yes)
			(effects
				(font
					(size 1.27 1.016)
					(thickness 0.1524)
				)
			)
		)
		(duplicate_pad_numbers_are_jumpers no)
		(fp_line
			(start 0.635 0)
			(end -0.635 0)
			(stroke
				(width 0.508)
				(type default)
			)
			(layer "F.SilkS")
		)
		(fp_rect
			(start -0.9652 1.778)
			(end 0.9652 -1.778)
			(stroke
				(width 0)
				(type default)
			)
			(fill no)
			(layer "F.CrtYd")
		)
		(fp_poly
			(pts
				(xy -0.9652 -1.778) (xy 0.9652 -1.778) (xy 0.9652 1.778) (xy -0.9652 1.778)
			)
			(stroke
				(width 0)
				(type default)
			)
			(fill no)
			(layer "F.Fab")
		)
		(pad "1" smd rect
			(at 0 -0.9652 90)
			(size 1.397 1.143)
			(layers "F.Cu" "F.Mask" "F.Paste")
			(net "VR_FET_SW_P12V_STBY_PVPP_GHJ")
		)
		(pad "2" smd rect
			(at 0 0.9652 90)
			(size 1.397 1.143)
			(layers "F.Cu" "F.Mask" "F.Paste")
			(net "GND")
		)
	)
	(footprint ""
		(layer "F.Cu")
		(at 408.520392 -10.916666)
		(property "Reference" "C8G8"
			(at 0 0 0)
			(layer "F.SilkS")
			(hide yes)
			(effects
				(font
					(size 1.27 1.27)
				)
			)
		)
		(property "Value" ""
			(at 0 0 0)
			(layer "F.Fab")
			(effects
				(font
					(size 1.27 1.27)
				)
			)
		)
		(duplicate_pad_numbers_are_jumpers no)
		(fp_rect
			(start -0.3048 0.9906)
			(end 0.3048 -0.1016)
			(stroke
				(width 0)
				(type default)
			)
			(fill no)
			(layer "F.CrtYd")
		)
		(fp_line
			(start -0.3048 -0.1016)
			(end -0.3048 0.9906)
			(stroke
				(width 0.1)
				(type default)
			)
			(layer "F.Fab")
		)
		(fp_line
			(start -0.3048 0.9906)
			(end 0.3048 0.9906)
			(stroke
				(width 0.1)
				(type default)
			)
			(layer "F.Fab")
		)
		(fp_line
			(start 0.3048 -0.1016)
			(end -0.3048 -0.1016)
			(stroke
				(width 0.1)
				(type default)
			)
			(layer "F.Fab")
		)
		(fp_line
			(start 0.3048 0.9906)
			(end 0.3048 -0.1016)
			(stroke
				(width 0.1)
				(type default)
			)
			(layer "F.Fab")
		)
		(pad "1" smd rect
			(at 0 0)
			(size 0.508 0.508)
			(layers "F.Cu" "F.Mask" "F.Paste")
			(net "P3E_CPU0_PE2_SS_TXP<1>")
		)
		(pad "2" smd rect
			(at 0 0.889)
			(size 0.508 0.508)
			(layers "F.Cu" "F.Mask" "F.Paste")
			(net "P3E_CPU0_PE2_SS_C_TXP<1>")
		)
		(zone
			(layer "F.Cu")
			(hatch none 0.5)
			(connect_pads
				(clearance 0)
			)
			(min_thickness 0.25)
			(keepout
				(tracks not_allowed)
				(vias allowed)
				(pads allowed)
				(copperpour not_allowed)
				(footprints allowed)
			)
			(placement
				(enabled no)
				(sheetname "")
			)
			(fill
				(thermal_gap 0.5)
				(thermal_bridge_width 0.5)
				(island_removal_mode 0)
			)
			(polygon
				(pts
					(xy 408.266392 -10.281666) (xy 408.774392 -10.281666) (xy 408.774392 -10.662666) (xy 408.266392 -10.662666)
				)
			)
		)
		(zone
			(layer "F.Cu")
			(hatch none 0.5)
			(connect_pads
				(clearance 0)
			)
			(min_thickness 0.25)
			(keepout
				(tracks allowed)
				(vias not_allowed)
				(pads allowed)
				(copperpour not_allowed)
				(footprints allowed)
			)
			(placement
				(enabled no)
				(sheetname "")
			)
			(fill
				(thermal_gap 0.5)
				(thermal_bridge_width 0.5)
				(island_removal_mode 0)
			)
			(polygon
				(pts
					(xy 408.266392 -10.281666) (xy 408.774392 -10.281666) (xy 408.774392 -10.662666) (xy 408.266392 -10.662666)
				)
			)
		)
	)
)
